# T6G (Grand Teton) — schematic netlist excerpt (pin names and nets, part order shuffled) for the footprints in the layout excerpt that follows; sources: Cadence DE-HDL packaged netlist, KiCad conversion of 04192023_DAF0TMB3IC0_F0TG_MB_C_brd_V02_OCP.brd

R8025  Q_RES  560 1% CHIP  pkg 0402LF  page 256 : A = LED_P12V_PSU_R1 ; B = LED_P12V_PSU_R2
R3845  Q_RES  0 5% EMPTY  pkg 0402LF  page 135 : A = P3V3_OCP_SFF_EN_R ; B = P3V3_OCP_EN_1_R2

(kicad_pcb
	(version 20260206)
	(generator "pcbnew")
	(generator_version "10.0")
	(general
		(thickness 1.6)
		(legacy_teardrops no)
	)
	(paper "A4")
	(title_block
		(title "04192023_DAF0TMB3IC0_F0TG_MB_C_brd_V02_OCP.brd")
		(comment 1 "Grand Teton / footprints 450-451 of 8354")
	)
	(layers
		(0 "F.Cu" signal "TOP")
		(4 "In1.Cu" signal "GND")
		(6 "In2.Cu" signal "IN1")
		(8 "In3.Cu" signal "GND1")
		(10 "In4.Cu" signal "IN2")
		(12 "In5.Cu" signal "GND2")
		(14 "In6.Cu" signal "IN3")
		(16 "In7.Cu" signal "GND3")
		(18 "In8.Cu" signal "VCC")
		(20 "In9.Cu" signal "VCC1")
		(22 "In10.Cu" signal "GND4")
		(24 "In11.Cu" signal "IN4")
		(26 "In12.Cu" signal "GND5")
		(28 "In13.Cu" signal "IN5")
		(30 "In14.Cu" signal "GND6")
		(32 "In15.Cu" signal "IN6")
		(34 "In16.Cu" signal "GND7")
		(2 "B.Cu" signal "BOTTOM")
		(9 "F.Adhes" user "F.Adhesive")
		(11 "B.Adhes" user "B.Adhesive")
		(13 "F.Paste" user "Package Geometry/Pastemask Top")
		(15 "B.Paste" user "Package Geometry/Pastemask Bottom")
		(5 "F.SilkS" user "Ref Des/Silkscreen Top")
		(7 "B.SilkS" user "Ref Des/Silkscreen Bottom")
		(1 "F.Mask" user "Board Geometry/Soldermask Top")
		(3 "B.Mask" user "Board Geometry/Soldermask Bottom")
		(17 "Dwgs.User" user "User.Drawings")
		(19 "Cmts.User" user "User.Comments")
		(21 "Eco1.User" user "User.Eco1")
		(23 "Eco2.User" user "User.Eco2")
		(25 "Edge.Cuts" user "Board Geometry/Outline")
		(27 "Margin" user)
		(31 "F.CrtYd" user "Package Geometry/Place Bound Top")
		(29 "B.CrtYd" user "Package Geometry/Place Bound Bottom")
		(35 "F.Fab" user "Ref Des/Assembly Top")
		(33 "B.Fab" user "Ref Des/Assembly Bottom")
	)
	(footprint ""
		(layer "F.Cu")
		(at 38.180772 -55.869332 -90)
		(property "Reference" "R8025"
			(at 0 0 270)
			(layer "F.SilkS")
			(hide yes)
			(effects
				(font
					(size 1.27 1.27)
				)
			)
		)
		(property "Value" ""
			(at 0 0 270)
			(layer "F.Fab")
			(effects
				(font
					(size 1.27 1.27)
				)
			)
		)
		(duplicate_pad_numbers_are_jumpers no)
		(fp_line
			(start -0.7874 0.4064)
			(end -0.7874 -0.4064)
			(stroke
				(width 0.1524)
				(type default)
			)
			(layer "F.SilkS")
		)
		(fp_line
			(start 0.7874 0.4064)
			(end -0.7874 0.4064)
			(stroke
				(width 0.1524)
				(type default)
			)
			(layer "F.SilkS")
		)
		(fp_line
			(start -0.7874 -0.4064)
			(end 0.7874 -0.4064)
			(stroke
				(width 0.1524)
				(type default)
			)
			(layer "F.SilkS")
		)
		(fp_line
			(start 0.7874 -0.4064)
			(end 0.7874 0.4064)
			(stroke
				(width 0.1524)
				(type default)
			)
			(layer "F.SilkS")
		)
		(fp_line
			(start -0.67945 0.3048)
			(end -0.67945 -0.305054)
			(stroke
				(width 0.1)
				(type default)
			)
			(layer "F.Fab")
		)
		(fp_line
			(start -0.12065 0.3048)
			(end -0.67945 0.3048)
			(stroke
				(width 0.1)
				(type default)
			)
			(layer "F.Fab")
		)
		(fp_line
			(start 0.120396 0.3048)
			(end 0.120396 0.2794)
			(stroke
				(width 0.1)
				(type default)
			)
			(layer "F.Fab")
		)
		(fp_line
			(start 0.67945 0.3048)
			(end 0.120396 0.3048)
			(stroke
				(width 0.1)
				(type default)
			)
			(layer "F.Fab")
		)
		(fp_line
			(start -0.12065 0.2794)
			(end -0.12065 0.3048)
			(stroke
				(width 0.1)
				(type default)
			)
			(layer "F.Fab")
		)
		(fp_line
			(start 0.120396 0.2794)
			(end -0.12065 0.2794)
			(stroke
				(width 0.1)
				(type default)
			)
			(layer "F.Fab")
		)
		(fp_line
			(start -0.12065 -0.2794)
			(end 0.12065 -0.2794)
			(stroke
				(width 0.1)
				(type default)
			)
			(layer "F.Fab")
		)
		(fp_line
			(start 0.12065 -0.2794)
			(end 0.12065 -0.3048)
			(stroke
				(width 0.1)
				(type default)
			)
			(layer "F.Fab")
		)
		(fp_line
			(start 0.12065 -0.3048)
			(end 0.67945 -0.3048)
			(stroke
				(width 0.1)
				(type default)
			)
			(layer "F.Fab")
		)
		(fp_line
			(start 0.67945 -0.3048)
			(end 0.67945 0.3048)
			(stroke
				(width 0.1)
				(type default)
			)
			(layer "F.Fab")
		)
		(fp_line
			(start -0.67945 -0.305054)
			(end -0.12065 -0.305054)
			(stroke
				(width 0.1)
				(type default)
			)
			(layer "F.Fab")
		)
		(fp_line
			(start -0.12065 -0.305054)
			(end -0.12065 -0.2794)
			(stroke
				(width 0.1)
				(type default)
			)
			(layer "F.Fab")
		)
		(pad "1" smd circle
			(at -0.40005 0 270)
			(size 0 0)
			(layers "F.Cu" "F.Mask" "F.Paste")
			(net "LED_P12V_PSU_R1")
		)
		(pad "2" smd circle
			(at 0.40005 0 270)
			(size 0 0)
			(layers "F.Cu" "F.Mask" "F.Paste")
			(net "LED_P12V_PSU_R2")
		)
	)
	(footprint ""
		(layer "F.Cu")
		(at 420.06266 -109.231176 -90)
		(property "Reference" "R3845"
			(at 0 0 270)
			(layer "F.SilkS")
			(hide yes)
			(effects
				(font
					(size 1.27 1.27)
				)
			)
		)
		(property "Value" ""
			(at 0 0 270)
			(layer "F.Fab")
			(effects
				(font
					(size 1.27 1.27)
				)
			)
		)
		(duplicate_pad_numbers_are_jumpers no)
		(fp_line
			(start -0.7874 0.4064)
			(end -0.7874 -0.4064)
			(stroke
				(width 0.1524)
				(type default)
			)
			(layer "F.SilkS")
		)
		(fp_line
			(start 0.7874 0.4064)
			(end -0.7874 0.4064)
			(stroke
				(width 0.1524)
				(type default)
			)
			(layer "F.SilkS")
		)
		(fp_line
			(start -0.7874 -0.4064)
			(end 0.7874 -0.4064)
			(stroke
				(width 0.1524)
				(type default)
			)
			(layer "F.SilkS")
		)
		(fp_line
			(start 0.7874 -0.4064)
			(end 0.7874 0.4064)
			(stroke
				(width 0.1524)
				(type default)
			)
			(layer "F.SilkS")
		)
		(fp_line
			(start -0.67945 0.3048)
			(end -0.67945 -0.305054)
			(stroke
				(width 0.1)
				(type default)
			)
			(layer "F.Fab")
		)
		(fp_line
			(start -0.12065 0.3048)
			(end -0.67945 0.3048)
			(stroke
				(width 0.1)
				(type default)
			)
			(layer "F.Fab")
		)
		(fp_line
			(start 0.120396 0.3048)
			(end 0.120396 0.2794)
			(stroke
				(width 0.1)
				(type default)
			)
			(layer "F.Fab")
		)
		(fp_line
			(start 0.67945 0.3048)
			(end 0.120396 0.3048)
			(stroke
				(width 0.1)
				(type default)
			)
			(layer "F.Fab")
		)
		(fp_line
			(start -0.12065 0.2794)
			(end -0.12065 0.3048)
			(stroke
				(width 0.1)
				(type default)
			)
			(layer "F.Fab")
		)
		(fp_line
			(start 0.120396 0.2794)
			(end -0.12065 0.2794)
			(stroke
				(width 0.1)
				(type default)
			)
			(layer "F.Fab")
		)
		(fp_line
			(start -0.12065 -0.2794)
			(end 0.12065 -0.2794)
			(stroke
				(width 0.1)
				(type default)
			)
			(layer "F.Fab")
		)
		(fp_line
			(start 0.12065 -0.2794)
			(end 0.12065 -0.3048)
			(stroke
				(width 0.1)
				(type default)
			)
			(layer "F.Fab")
		)
		(fp_line
			(start 0.12065 -0.3048)
			(end 0.67945 -0.3048)
			(stroke
				(width 0.1)
				(type default)
			)
			(layer "F.Fab")
		)
		(fp_line
			(start 0.67945 -0.3048)
			(end 0.67945 0.3048)
			(stroke
				(width 0.1)
				(type default)
			)
			(layer "F.Fab")
		)
		(fp_line
			(start -0.67945 -0.305054)
			(end -0.12065 -0.305054)
			(stroke
				(width 0.1)
				(type default)
			)
			(layer "F.Fab")
		)
		(fp_line
			(start -0.12065 -0.305054)
			(end -0.12065 -0.2794)
			(stroke
				(width 0.1)
				(type default)
			)
			(layer "F.Fab")
		)
		(pad "1" smd circle
			(at -0.40005 0 270)
			(size 0 0)
			(layers "F.Cu" "F.Mask" "F.Paste")
			(net "P3V3_OCP_SFF_EN_R")
		)
		(pad "2" smd circle
			(at 0.40005 0 270)
			(size 0 0)
			(layers "F.Cu" "F.Mask" "F.Paste")
			(net "P3V3_OCP_EN_1_R2")
		)
	)
)
